(kicad_pcb
	(version 20260206)
	(generator "pcbnew")
	(generator_version "10.0")
	(general
		(thickness 1.6)
		(legacy_teardrops no)
	)
	(paper "A4")
	(title_block
		(title "pdpb — Lightning_PDPB_BRD.brd")
		(comment 1 "Lightning (Wiwynn / Facebook NVMe JBOF) / footprints 909-909 of 1140")
	)
	(layers
		(0 "F.Cu" signal "TOP")
		(4 "In1.Cu" signal "L2GND")
		(6 "In2.Cu" signal "L3")
		(8 "In3.Cu" signal "L4VCC")
		(10 "In4.Cu" signal "L5VCC")
		(12 "In5.Cu" signal "L6")
		(14 "In6.Cu" signal "L7GND")
		(2 "B.Cu" signal "BOTTOM")
		(9 "F.Adhes" user "F.Adhesive")
		(11 "B.Adhes" user "B.Adhesive")
		(13 "F.Paste" user "Package Geometry/Pastemask Top")
		(15 "B.Paste" user "Package Geometry/Pastemask Bottom")
		(5 "F.SilkS" user "Ref Des/Silkscreen Top")
		(7 "B.SilkS" user "Ref Des/Silkscreen Bottom")
		(1 "F.Mask" user "Board Geometry/Soldermask Top")
		(3 "B.Mask" user "Board Geometry/Soldermask Bottom")
		(17 "Dwgs.User" user "User.Drawings")
		(19 "Cmts.User" user "User.Comments")
		(21 "Eco1.User" user "User.Eco1")
		(23 "Eco2.User" user "User.Eco2")
		(25 "Edge.Cuts" user "Board Geometry/Outline")
		(27 "Margin" user)
		(31 "F.CrtYd" user "Package Geometry/Place Bound Top")
		(29 "B.CrtYd" user "Package Geometry/Place Bound Bottom")
		(35 "F.Fab" user "Ref Des/Assembly Top")
		(33 "B.Fab" user "Ref Des/Assembly Bottom")
	)
	(footprint ""
		(layer "F.Cu")
		(at 41.150032 -376.670062 90)
		(property "Reference" "J6"
			(at 0 0 90)
			(layer "F.SilkS")
			(hide yes)
			(effects
				(font
					(size 1.27 1.27)
				)
			)
		)
		(property "Value" "PCISLT68-14-GP-U1"
			(at -22.225 12.7508 90)
			(unlocked yes)
			(layer "F.Fab")
			(hide yes)
			(effects
				(font
					(size 1.016 1.016)
					(thickness 0.1524)
				)
			)
		)
		(property "Device Type" "SD-78827-0001"
			(at -22.225 11.2268 90)
			(unlocked yes)
			(layer "F.Fab")
			(hide yes)
			(effects
				(font
					(size 1.016 1.016)
					(thickness 0.1524)
				)
			)
		)
		(duplicate_pad_numbers_are_jumpers no)
		(fp_line
			(start 20.4724 -3.4036)
			(end 20.4724 0.0254)
			(stroke
				(width 0.1524)
				(type default)
			)
			(layer "F.SilkS")
		)
		(fp_line
			(start -20.4724 -3.4036)
			(end 20.4724 -3.4036)
			(stroke
				(width 0.1524)
				(type default)
			)
			(layer "F.SilkS")
		)
		(fp_line
			(start 23.749 0.0254)
			(end 23.749 4.6736)
			(stroke
				(width 0.1524)
				(type default)
			)
			(layer "F.SilkS")
		)
		(fp_line
			(start 20.4724 0.0254)
			(end 23.749 0.0254)
			(stroke
				(width 0.1524)
				(type default)
			)
			(layer "F.SilkS")
		)
		(fp_line
			(start -20.4724 0.0254)
			(end -20.4724 -3.4036)
			(stroke
				(width 0.1524)
				(type default)
			)
			(layer "F.SilkS")
		)
		(fp_line
			(start -23.749 0.0254)
			(end -20.4724 0.0254)
			(stroke
				(width 0.1524)
				(type default)
			)
			(layer "F.SilkS")
		)
		(fp_line
			(start 23.117556 1.803908)
			(end 23.117556 2.896108)
			(stroke
				(width 0.3048)
				(type default)
			)
			(layer "F.SilkS")
		)
		(fp_line
			(start -20.882356 1.803908)
			(end -20.882356 2.896108)
			(stroke
				(width 0.3048)
				(type default)
			)
			(layer "F.SilkS")
		)
		(fp_line
			(start 20.882356 2.896108)
			(end 20.882356 1.803908)
			(stroke
				(width 0.3048)
				(type default)
			)
			(layer "F.SilkS")
		)
		(fp_line
			(start -23.117556 2.896108)
			(end -23.117556 1.803908)
			(stroke
				(width 0.3048)
				(type default)
			)
			(layer "F.SilkS")
		)
		(fp_line
			(start 23.749 4.6736)
			(end 20.4724 4.6736)
			(stroke
				(width 0.1524)
				(type default)
			)
			(layer "F.SilkS")
		)
		(fp_line
			(start 20.4724 4.6736)
			(end 20.4724 12.0142)
			(stroke
				(width 0.1524)
				(type default)
			)
			(layer "F.SilkS")
		)
		(fp_line
			(start -20.4724 4.6736)
			(end -23.749 4.6736)
			(stroke
				(width 0.1524)
				(type default)
			)
			(layer "F.SilkS")
		)
		(fp_line
			(start -23.749 4.6736)
			(end -23.749 0.0254)
			(stroke
				(width 0.1524)
				(type default)
			)
			(layer "F.SilkS")
		)
		(fp_line
			(start 17.8435 10.3124)
			(end -17.8435 10.3124)
			(stroke
				(width 0.1524)
				(type default)
			)
			(layer "F.SilkS")
		)
		(fp_line
			(start -17.8435 10.3124)
			(end -17.8435 12.0142)
			(stroke
				(width 0.1524)
				(type default)
			)
			(layer "F.SilkS")
		)
		(fp_line
			(start 20.4724 12.0142)
			(end 17.8435 12.0142)
			(stroke
				(width 0.1524)
				(type default)
			)
			(layer "F.SilkS")
		)
		(fp_line
			(start 17.8435 12.0142)
			(end 17.8435 10.3124)
			(stroke
				(width 0.1524)
				(type default)
			)
			(layer "F.SilkS")
		)
		(fp_line
			(start -17.8435 12.0142)
			(end -20.4724 12.0142)
			(stroke
				(width 0.1524)
				(type default)
			)
			(layer "F.SilkS")
		)
		(fp_line
			(start -20.4724 12.0142)
			(end -20.4724 4.6736)
			(stroke
				(width 0.1524)
				(type default)
			)
			(layer "F.SilkS")
		)
		(fp_arc
			(start 20.882356 1.803908)
			(mid 21.999956 0.686308)
			(end 23.117556 1.803908)
			(stroke
				(width 0.3048)
				(type default)
			)
			(layer "F.SilkS")
		)
		(fp_arc
			(start -23.117556 1.803908)
			(mid -21.999956 0.686308)
			(end -20.882356 1.803908)
			(stroke
				(width 0.3048)
				(type default)
			)
			(layer "F.SilkS")
		)
		(fp_arc
			(start 23.117556 2.896108)
			(mid 21.999956 4.013708)
			(end 20.882356 2.896108)
			(stroke
				(width 0.3048)
				(type default)
			)
			(layer "F.SilkS")
		)
		(fp_arc
			(start -20.882356 2.896108)
			(mid -21.999956 4.013708)
			(end -23.117556 2.896108)
			(stroke
				(width 0.3048)
				(type default)
			)
			(layer "F.SilkS")
		)
		(fp_poly
			(pts
				(xy -20.2184 11.7602) (xy -20.2184 4.4196) (xy -23.495 4.4196) (xy -23.495 0.2794) (xy -20.2184 0.2794)
				(xy -20.2184 -3.1496) (xy 20.2184 -3.1496) (xy 20.2184 0.2794) (xy 23.495 0.2794) (xy 23.495 4.4196)
				(xy 20.2184 4.4196) (xy 20.2184 11.7602) (xy 18.0975 11.7602) (xy 18.0975 10.0584) (xy -18.0975 10.0584)
				(xy -18.0975 11.7602)
			)
			(stroke
				(width 0)
				(type default)
			)
			(fill no)
			(layer "F.CrtYd")
		)
		(fp_poly
			(pts
				(xy -21.2471 16.256) (xy -21.2471 4.9276) (xy -24.003 4.9276) (xy -24.003 -0.2286) (xy -20.7264 -0.2286)
				(xy -20.7264 -3.6576) (xy 20.7264 -3.6576) (xy 20.7264 -0.2286) (xy 24.003 -0.2286) (xy 24.003 -0.00635)
				(xy 20.2184 -0.00635) (xy 20.2184 -3.1496) (xy -20.2184 -3.1496) (xy -20.2184 0.2794) (xy -23.495 0.2794)
				(xy -23.495 4.4196) (xy -20.2184 4.4196) (xy -20.2184 11.7602) (xy -18.0975 11.7602) (xy -18.0975 10.0584)
				(xy 18.0975 10.0584) (xy 18.0975 11.7602) (xy 20.2184 11.7602) (xy 20.2184 4.4196) (xy 23.495 4.4196)
				(xy 23.495 0.2794) (xy 20.2184 0.2794) (xy 20.2184 0.00635) (xy 24.003 0.00635) (xy 24.003 4.9276)
				(xy 21.2471 4.9276) (xy 21.2471 16.256)
			)
			(stroke
				(width 0)
				(type default)
			)
			(fill no)
			(layer "F.CrtYd")
		)
		(fp_poly
			(pts
				(xy -21.2471 16.256) (xy -21.2471 4.9276) (xy -24.003 4.9276) (xy -24.003 -0.2286) (xy -20.7264 -0.2286)
				(xy -20.7264 -3.6576) (xy 20.7264 -3.6576) (xy 20.7264 -0.2286) (xy 24.003 -0.2286) (xy 24.003 4.9276)
				(xy 21.2471 4.9276) (xy 21.2471 16.256)
			)
			(stroke
				(width 0)
				(type default)
			)
			(fill no)
			(layer "F.Fab")
		)
		(pad "" np_thru_hole circle
			(at -18.999962 0 90)
			(size 0.254 0.254)
			(drill 1.8542)
			(layers "*.Cu" "*.Mask")
			(clearance 1.1557)
			(thermal_gap 1.1557)
		)
		(pad "" np_thru_hole circle
			(at 18.999962 0 90)
			(size 0.254 0.254)
			(drill 1.8542)
			(layers "*.Cu" "*.Mask")
			(clearance 1.1557)
			(thermal_gap 1.1557)
		)
		(pad "E1" smd rect
			(at -7.079996 1.240028 90)
			(size 0.508 2.0066)
			(layers "F.Cu" "F.Mask" "F.Paste")
			(net "PE_CLK100M_DR6_2_P")
		)
		(pad "E2" smd rect
			(at -6.279896 1.240028 90)
			(size 0.508 2.0066)
			(layers "F.Cu" "F.Mask" "F.Paste")
			(net "PE_CLK100M_DR6_2_N")
		)
		(pad "E3" smd rect
			(at -5.48005 1.240028 90)
			(size 0.508 2.0066)
			(layers "F.Cu" "F.Mask" "F.Paste")
			(net "P3V3")
		)
		(pad "E4" smd rect
			(at -4.67995 1.240028 90)
			(size 0.508 2.0066)
			(layers "F.Cu" "F.Mask" "F.Paste")
			(net "SSD6_PERST_N")
		)
		(pad "E5" smd rect
			(at -3.880104 1.240028 90)
			(size 0.508 2.0066)
			(layers "F.Cu" "F.Mask" "F.Paste")
			(net "SSD6_PERST_N")
		)
		(pad "E6" smd rect
			(at -3.080004 1.240028 90)
			(size 0.508 2.0066)
			(layers "F.Cu" "F.Mask" "F.Paste")
			(net "Net_1125")
		)
		(pad "E7" smd rect
			(at -15.48003 -1.949958 90)
			(size 0.508 2.0066)
			(layers "F.Cu" "F.Mask" "F.Paste")
			(net "PE_CLK100M_DR6_1_P")
		)
		(pad "E8" smd rect
			(at -14.67993 -1.949958 90)
			(size 0.508 2.0066)
			(layers "F.Cu" "F.Mask" "F.Paste")
			(net "PE_CLK100M_DR6_1_N")
		)
		(pad "E9" smd rect
			(at -13.880084 -1.949958 90)
			(size 0.508 2.0066)
			(layers "F.Cu" "F.Mask" "F.Paste")
			(net "GND")
		)
		(pad "E10" smd rect
			(at -13.079984 -1.949958 90)
			(size 0.508 2.0066)
			(layers "F.Cu" "F.Mask" "F.Paste")
			(net "PE_TX1_DR6_N")
		)
		(pad "E11" smd rect
			(at -12.279884 -1.949958 90)
			(size 0.508 2.0066)
			(layers "F.Cu" "F.Mask" "F.Paste")
			(net "PE_TX1_DR6_P")
		)
		(pad "E12" smd rect
			(at -11.480038 -1.949958 90)
			(size 0.508 2.0066)
			(layers "F.Cu" "F.Mask" "F.Paste")
			(net "GND")
		)
		(pad "E13" smd rect
			(at -10.679938 -1.949958 90)
			(size 0.508 2.0066)
			(layers "F.Cu" "F.Mask" "F.Paste")
			(net "PE_RX1_DR6_N")
		)
		(pad "E14" smd rect
			(at -9.880092 -1.949958 90)
			(size 0.508 2.0066)
			(layers "F.Cu" "F.Mask" "F.Paste")
			(net "PE_RX1_DR6_P")
		)
		(pad "E15" smd rect
			(at -9.079992 -1.949958 90)
			(size 0.508 2.0066)
			(layers "F.Cu" "F.Mask" "F.Paste")
			(net "GND")
		)
		(pad "E16" smd rect
			(at -8.279892 -1.949958 90)
			(size 0.508 2.0066)
			(layers "F.Cu" "F.Mask" "F.Paste")
			(net "Net_1132")
		)
		(pad "E17" smd rect
			(at 9.320022 -1.949958 90)
			(size 0.508 2.0066)
			(layers "F.Cu" "F.Mask" "F.Paste")
			(net "PE_TX4_DR6_N")
		)
		(pad "E18" smd rect
			(at 10.120122 -1.949958 90)
			(size 0.508 2.0066)
			(layers "F.Cu" "F.Mask" "F.Paste")
			(net "PE_TX4_DR6_P")
		)
		(pad "E19" smd rect
			(at 10.919968 -1.949958 90)
			(size 0.508 2.0066)
			(layers "F.Cu" "F.Mask" "F.Paste")
			(net "GND")
		)
		(pad "E20" smd rect
			(at 11.720068 -1.949958 90)
			(size 0.508 2.0066)
			(layers "F.Cu" "F.Mask" "F.Paste")
			(net "PE_RX4_DR6_N")
		)
		(pad "E21" smd rect
			(at 12.519914 -1.949958 90)
			(size 0.508 2.0066)
			(layers "F.Cu" "F.Mask" "F.Paste")
			(net "PE_RX4_DR6_P")
		)
		(pad "E22" smd rect
			(at 13.320014 -1.949958 90)
			(size 0.508 2.0066)
			(layers "F.Cu" "F.Mask" "F.Paste")
			(net "GND")
		)
		(pad "E23" smd rect
			(at 14.120114 -1.949958 90)
			(size 0.508 2.0066)
			(layers "F.Cu" "F.Mask" "F.Paste")
			(net "SCL_DR6_R")
		)
		(pad "E24" smd rect
			(at 14.91996 -1.949958 90)
			(size 0.508 2.0066)
			(layers "F.Cu" "F.Mask" "F.Paste")
			(net "SDA_DR6_R")
		)
		(pad "E25" smd rect
			(at 15.72006 -1.949958 90)
			(size 0.508 2.0066)
			(layers "F.Cu" "F.Mask" "F.Paste")
			(net "DUALPORTEN#6")
		)
		(pad "P1" smd rect
			(at -1.905 0.824992 90)
			(size 0.6604 2.0574)
			(layers "F.Cu" "F.Mask" "F.Paste")
			(net "Net_1128")
		)
		(pad "P2" smd rect
			(at -0.635 0.824992 90)
			(size 0.6604 2.0574)
			(layers "F.Cu" "F.Mask" "F.Paste")
			(net "Net_1127")
		)
		(pad "P3" smd rect
			(at 0.635 0.824992 90)
			(size 0.6604 2.0574)
			(layers "F.Cu" "F.Mask" "F.Paste")
			(net "Net_1126")
		)
		(pad "P4" smd rect
			(at 1.905 0.824992 90)
			(size 0.6604 2.0574)
			(layers "F.Cu" "F.Mask" "F.Paste")
			(net "SSD6_CLK0_OE_N")
		)
		(pad "P5" smd rect
			(at 3.175 0.824992 90)
			(size 0.6604 2.0574)
			(layers "F.Cu" "F.Mask" "F.Paste")
			(net "GND")
		)
		(pad "P6" smd rect
			(at 4.445 0.824992 90)
			(size 0.6604 2.0574)
			(layers "F.Cu" "F.Mask" "F.Paste")
			(net "GND")
		)
		(pad "P7" smd rect
			(at 5.715 0.824992 90)
			(size 0.6604 2.0574)
			(layers "F.Cu" "F.Mask" "F.Paste")
			(net "Net_100")
		)
		(pad "P8" smd rect
			(at 6.985 0.824992 90)
			(size 0.6604 2.0574)
			(layers "F.Cu" "F.Mask" "F.Paste")
			(net "Net_73")
		)
		(pad "P9" smd rect
			(at 8.255 0.824992 90)
			(size 0.6604 2.0574)
			(layers "F.Cu" "F.Mask" "F.Paste")
			(net "Net_87")
		)
		(pad "P10" smd rect
			(at 9.525 0.824992 90)
			(size 0.6604 2.0574)
			(layers "F.Cu" "F.Mask" "F.Paste")
			(net "SSD_PRSNT_NET6")
		)
		(pad "P11" smd rect
			(at 10.795 0.824992 90)
			(size 0.6604 2.0574)
			(layers "F.Cu" "F.Mask" "F.Paste")
			(net "SSD_ACT_DR6")
		)
		(pad "P12" smd rect
			(at 12.065 0.824992 90)
			(size 0.6604 2.0574)
			(layers "F.Cu" "F.Mask" "F.Paste")
			(net "GND")
		)
		(pad "P13" smd rect
			(at 13.335 0.824992 90)
			(size 0.6604 2.0574)
			(layers "F.Cu" "F.Mask" "F.Paste")
			(net "12V_PRECH_SSD6")
		)
		(pad "P14" smd rect
			(at 14.605 0.824992 90)
			(size 0.6604 2.0574)
			(layers "F.Cu" "F.Mask" "F.Paste")
			(net "P12V_SSD6")
		)
		(pad "P15" smd rect
			(at 15.875 0.824992 90)
			(size 0.6604 2.0574)
			(layers "F.Cu" "F.Mask" "F.Paste")
			(net "P12V_SSD6")
		)
		(pad "PTH1" thru_hole oval
			(at -21.999956 2.350008 90)
			(size 1.524 2.6162)
			(drill oval 0.8128 1.905)
			(layers "*.Cu" "*.Mask")
			(remove_unused_layers no)
			(net "Net_1137")
			(clearance 0.1524)
			(thermal_gap 0.1524)
		)
		(pad "PTH2" thru_hole oval
			(at 21.999956 2.350008 90)
			(size 1.524 2.6162)
			(drill oval 0.8128 1.905)
			(layers "*.Cu" "*.Mask")
			(remove_unused_layers no)
			(net "Net_1121")
			(clearance 0.1524)
			(thermal_gap 0.1524)
		)
		(pad "S1" smd rect
			(at -15.875 0.824992 90)
			(size 0.6604 2.0574)
			(layers "F.Cu" "F.Mask" "F.Paste")
			(net "GND")
		)
		(pad "S2" smd rect
			(at -14.605 0.824992 90)
			(size 0.6604 2.0574)
			(layers "F.Cu" "F.Mask" "F.Paste")
			(net "Net_1136")
		)
		(pad "S3" smd rect
			(at -13.335 0.824992 90)
			(size 0.6604 2.0574)
			(layers "F.Cu" "F.Mask" "F.Paste")
			(net "Net_1135")
		)
		(pad "S4" smd rect
			(at -12.065 0.824992 90)
			(size 0.6604 2.0574)
			(layers "F.Cu" "F.Mask" "F.Paste")
			(net "GND")
		)
		(pad "S5" smd rect
			(at -10.795 0.824992 90)
			(size 0.6604 2.0574)
			(layers "F.Cu" "F.Mask" "F.Paste")
			(net "Net_1134")
		)
		(pad "S6" smd rect
			(at -9.525 0.824992 90)
			(size 0.6604 2.0574)
			(layers "F.Cu" "F.Mask" "F.Paste")
			(net "Net_1133")
		)
		(pad "S7" smd rect
			(at -8.255 0.824992 90)
			(size 0.6604 2.0574)
			(layers "F.Cu" "F.Mask" "F.Paste")
			(net "GND")
		)
		(pad "S8" smd rect
			(at -7.480046 -1.949958 90)
			(size 0.508 2.0066)
			(layers "F.Cu" "F.Mask" "F.Paste")
			(net "GND")
		)
		(pad "S9" smd rect
			(at -6.679946 -1.949958 90)
			(size 0.508 2.0066)
			(layers "F.Cu" "F.Mask" "F.Paste")
			(net "Net_1131")
		)
		(pad "S10" smd rect
			(at -5.8801 -1.949958 90)
			(size 0.508 2.0066)
			(layers "F.Cu" "F.Mask" "F.Paste")
			(net "Net_1130")
		)
		(pad "S11" smd rect
			(at -5.08 -1.949958 90)
			(size 0.508 2.0066)
			(layers "F.Cu" "F.Mask" "F.Paste")
			(net "GND")
		)
		(pad "S12" smd rect
			(at -4.2799 -1.949958 90)
			(size 0.508 2.0066)
			(layers "F.Cu" "F.Mask" "F.Paste")
			(net "Net_1129")
		)
		(pad "S13" smd rect
			(at -3.480054 -1.949958 90)
			(size 0.508 2.0066)
			(layers "F.Cu" "F.Mask" "F.Paste")
			(net "Net_1124")
		)
		(pad "S14" smd rect
			(at -2.679954 -1.949958 90)
			(size 0.508 2.0066)
			(layers "F.Cu" "F.Mask" "F.Paste")
			(net "GND")
		)
		(pad "S15" smd rect
			(at -1.880108 -1.949958 90)
			(size 0.508 2.0066)
			(layers "F.Cu" "F.Mask" "F.Paste")
			(net "Net_1123")
		)
		(pad "S16" smd rect
			(at -1.080008 -1.949958 90)
			(size 0.508 2.0066)
			(layers "F.Cu" "F.Mask" "F.Paste")
			(net "GND")
		)
		(pad "S17" smd rect
			(at -0.279908 -1.949958 90)
			(size 0.508 2.0066)
			(layers "F.Cu" "F.Mask" "F.Paste")
			(net "PE_TX2_DR6_N")
		)
		(pad "S18" smd rect
			(at 0.519938 -1.949958 90)
			(size 0.508 2.0066)
			(layers "F.Cu" "F.Mask" "F.Paste")
			(net "PE_TX2_DR6_P")
		)
		(pad "S19" smd rect
			(at 1.320038 -1.949958 90)
			(size 0.508 2.0066)
			(layers "F.Cu" "F.Mask" "F.Paste")
			(net "GND")
		)
		(pad "S20" smd rect
			(at 2.119884 -1.949958 90)
			(size 0.508 2.0066)
			(layers "F.Cu" "F.Mask" "F.Paste")
			(net "PE_RX2_DR6_N")
		)
		(pad "S21" smd rect
			(at 2.919984 -1.949958 90)
			(size 0.508 2.0066)
			(layers "F.Cu" "F.Mask" "F.Paste")
			(net "PE_RX2_DR6_P")
		)
		(pad "S22" smd rect
			(at 3.720084 -1.949958 90)
			(size 0.508 2.0066)
			(layers "F.Cu" "F.Mask" "F.Paste")
			(net "GND")
		)
		(pad "S23" smd rect
			(at 4.51993 -1.949958 90)
			(size 0.508 2.0066)
			(layers "F.Cu" "F.Mask" "F.Paste")
			(net "PE_TX3_DR6_N")
		)
		(pad "S24" smd rect
			(at 5.32003 -1.949958 90)
			(size 0.508 2.0066)
			(layers "F.Cu" "F.Mask" "F.Paste")
			(net "PE_TX3_DR6_P")
		)
		(pad "S25" smd rect
			(at 6.119876 -1.949958 90)
			(size 0.508 2.0066)
			(layers "F.Cu" "F.Mask" "F.Paste")
			(net "GND")
		)
		(pad "S26" smd rect
			(at 6.919976 -1.949958 90)
			(size 0.508 2.0066)
			(layers "F.Cu" "F.Mask" "F.Paste")
			(net "PE_RX3_DR6_N")
		)
		(pad "S27" smd rect
			(at 7.720076 -1.949958 90)
			(size 0.508 2.0066)
			(layers "F.Cu" "F.Mask" "F.Paste")
			(net "PE_RX3_DR6_P")
		)
		(pad "S28" smd rect
			(at 8.519922 -1.949958 90)
			(size 0.508 2.0066)
			(layers "F.Cu" "F.Mask" "F.Paste")
			(net "GND")
		)
		(zone
			(layers "F.Cu" "B.Cu" "In1.Cu" "In2.Cu" "In3.Cu" "In4.Cu" "In5.Cu" "In6.Cu")
			(hatch none 0.5)
			(connect_pads
				(clearance 0)
			)
			(min_thickness 0.25)
			(keepout
				(tracks not_allowed)
				(vias allowed)
				(pads allowed)
				(copperpour not_allowed)
				(footprints allowed)
			)
			(placement
				(enabled no)
				(sheetname "")
			)
			(fill
				(thermal_gap 0.5)
				(thermal_bridge_width 0.5)
				(island_removal_mode 0)
			)
			(polygon
				(pts
					(arc
						(start 42.381932 -395.670024)
						(mid 39.918132 -395.670024)
						(end 42.381932 -395.670024)
					)
				)
			)
		)
		(zone
			(layers "F.Cu" "B.Cu" "In1.Cu" "In2.Cu" "In3.Cu" "In4.Cu" "In5.Cu" "In6.Cu")
			(hatch none 0.5)
			(connect_pads
				(clearance 0)
			)
			(min_thickness 0.25)
			(keepout
				(tracks not_allowed)
				(vias allowed)
				(pads allowed)
				(copperpour not_allowed)
				(footprints allowed)
			)
			(placement
				(enabled no)
				(sheetname "")
			)
			(fill
				(thermal_gap 0.5)
				(thermal_bridge_width 0.5)
				(island_removal_mode 0)
			)
			(polygon
				(pts
					(arc
						(start 42.381932 -357.6701)
						(mid 39.918132 -357.6701)
						(end 42.381932 -357.6701)
					)
				)
			)
		)
	)
)
